FILE_TYPE = MULTI_PHYS_TABLE;

PART 'BAS70057F'

{========================================================================================}
:VALUE          | PART_TYPE | MATERIAL | PART_NUMBER      = STANDARD | LIFECYCLE      | PART_NUMBER   | JEDEC_TYPE    | DESCRIPTION                                | MANUFTR | MANUF_PN       | RD_CMPLS_LVL | CMPLS_LVL | CLASS | DIP_SMD | FP_ECN | FROM_PJ  | DATA                     | EE_CHECK_LIST | STATUS | PSL | PREFERENCE | CREATOR | CREATEDAY  ;
{========================================================================================}
 'BAS70-05-7-F' | 'SMLF'    | 'IC'     | 'BC0BAS70Z01'(!) = 'End of Design'  | 'Comp-Approve'   | 'BC0BAS70Z01' |'SOT23_123XB'| 'DIODE SMD BAS70-05-7-F(70V,SHTKY,SOT-23)' | 'DDS'   | 'BAS70-05-7-F' | 'EP(V1)'     | 'EP(V1)'  | 'IC'  | ''      | ''     | 'S1D-OZ' | 'DDS_BAS70-04-05-06.pdf' | ''            | ''     | ''  | ''         | ''      | '20121220'
 'BAS70-05-7-F' | 'SMLF'    | 'EMPTY'  | 'BC0BAS70Z01'(!) = 'End of Design'  | 'Comp-Approve'   | 'BC0BAS70Z01' |'SOT23_123XB'| 'DIODE SMD BAS70-05-7-F(70V,SHTKY,SOT-23)' | 'DDS'   | 'BAS70-05-7-F' | 'EP(V1)'     | 'EP(V1)'  | 'IC'  | ''      | ''     | 'S1D-OZ' | 'DDS_BAS70-04-05-06.pdf' | ''            | ''     | ''  | ''         | ''      | '20121220'

END_PART

END.

